# TIMECARD (Time Appliance Project (Time Card)) — schematic netlist excerpt (pin names and nets, part order shuffled) for the footprints in the layout excerpt that follows; sources: Cadence DE-HDL packaged netlist, KiCad conversion of R4006-B0001-02_R01.brd

R324  RESISTOR  0OHM -  pkg SMC_0402R_H016  page 26 : \1\ = SG ; \2\ = UNNAMED_14_IS32FL3207QWLA3TRQFN
R298  RESISTOR  33OHM 1%  pkg SMC_0402R_H016  page 18 : \1\ = R_SHT3X_RST_N ; \2\ = FPGA_OUT_SHT3X_RST_N

(kicad_pcb
	(version 20260206)
	(generator "pcbnew")
	(generator_version "10.0")
	(general
		(thickness 1.6)
		(legacy_teardrops no)
	)
	(paper "A4")
	(title_block
		(title "timecard-production-celestica-r4006 — R4006-B0001-02_R01.brd")
		(comment 1 "Time Appliance Project (Time Card) / footprints 476-477 of 1113")
	)
	(layers
		(0 "F.Cu" signal "TOP")
		(4 "In1.Cu" signal "L02_GND1")
		(6 "In2.Cu" signal "L03_SIG1")
		(8 "In3.Cu" signal "L04_GND2")
		(10 "In4.Cu" signal "L05_VCC1")
		(12 "In5.Cu" signal "L06_VCC2")
		(14 "In6.Cu" signal "L07_GND3")
		(16 "In7.Cu" signal "L08_SIG2")
		(18 "In8.Cu" signal "L09_GND4")
		(2 "B.Cu" signal "BOTTOM")
		(9 "F.Adhes" user "F.Adhesive")
		(11 "B.Adhes" user "B.Adhesive")
		(13 "F.Paste" user "Package Geometry/Pastemask Top")
		(15 "B.Paste" user "Package Geometry/Pastemask Bottom")
		(5 "F.SilkS" user "Ref Des/Silkscreen Top")
		(7 "B.SilkS" user "Ref Des/Silkscreen Bottom")
		(1 "F.Mask" user "Board Geometry/Soldermask Top")
		(3 "B.Mask" user "Board Geometry/Soldermask Bottom")
		(17 "Dwgs.User" user "User.Drawings")
		(19 "Cmts.User" user "User.Comments")
		(21 "Eco1.User" user "User.Eco1")
		(23 "Eco2.User" user "User.Eco2")
		(25 "Edge.Cuts" user "Board Geometry/Outline")
		(27 "Margin" user)
		(31 "F.CrtYd" user "Package Geometry/Place Bound Top")
		(29 "B.CrtYd" user "Package Geometry/Place Bound Bottom")
		(35 "F.Fab" user "Ref Des/Assembly Top")
		(33 "B.Fab" user "Ref Des/Assembly Bottom")
	)
	(footprint ""
		(layer "F.Cu")
		(at 111.125 -99.441 180)
		(property "Reference" "R324"
			(at -3.302 3.13563 0)
			(unlocked yes)
			(layer "F.SilkS")
			(effects
				(font
					(size 0.7874 0.5842)
					(thickness 0.1524)
				)
			)
		)
		(property "Value" "VAL*"
			(at 0.02032 2.13233 180)
			(unlocked yes)
			(layer "F.Fab")
			(hide yes)
			(effects
				(font
					(size 0.7874 0.5842)
					(thickness 0.1524)
				)
			)
		)
		(property "Tolerance" "TOL*"
			(at 0.044704 3.05435 180)
			(unlocked yes)
			(layer "Cmts.User")
			(hide yes)
			(effects
				(font
					(size 0.7874 0.5842)
					(thickness 0.1524)
				)
			)
		)
		(property "User Part Number" "PARTNUM*"
			(at 0.02032 4.024884 180)
			(unlocked yes)
			(layer "Cmts.User")
			(hide yes)
			(effects
				(font
					(size 0.7874 0.5842)
					(thickness 0.1524)
				)
			)
		)
		(property "Device Type" "RESISTOR-G155-100R0-J0,0OHM,-"
			(at 0.008382 1.210564 180)
			(unlocked yes)
			(layer "F.Fab")
			(hide yes)
			(effects
				(font
					(size 0.7874 0.5842)
					(thickness 0.1524)
				)
			)
		)
		(duplicate_pad_numbers_are_jumpers no)
		(fp_line
			(start 1.143 0.5588)
			(end 1.143 -0.5588)
			(stroke
				(width 0.1)
				(type default)
			)
			(layer "F.SilkS")
		)
		(fp_line
			(start 1.143 -0.5588)
			(end -1.143 -0.5588)
			(stroke
				(width 0.1)
				(type default)
			)
			(layer "F.SilkS")
		)
		(fp_line
			(start -1.143 0.5588)
			(end 1.143 0.5588)
			(stroke
				(width 0.1)
				(type default)
			)
			(layer "F.SilkS")
		)
		(fp_line
			(start -1.143 -0.5588)
			(end -1.143 0.5588)
			(stroke
				(width 0.1)
				(type default)
			)
			(layer "F.SilkS")
		)
		(fp_poly
			(pts
				(xy -1.143 0.5588) (xy 1.143 0.5588) (xy 1.143 -0.5588) (xy -1.143 -0.5588)
			)
			(stroke
				(width 0)
				(type default)
			)
			(fill no)
			(layer "F.CrtYd")
		)
		(fp_line
			(start 0.508 0.3048)
			(end 0.508 -0.3048)
			(stroke
				(width 0.1)
				(type default)
			)
			(layer "F.Fab")
		)
		(fp_line
			(start 0.508 -0.3048)
			(end -0.508 -0.3048)
			(stroke
				(width 0.1)
				(type default)
			)
			(layer "F.Fab")
		)
		(fp_line
			(start -0.508 0.3048)
			(end 0.508 0.3048)
			(stroke
				(width 0.1)
				(type default)
			)
			(layer "F.Fab")
		)
		(fp_line
			(start -0.508 -0.3048)
			(end -0.508 0.3048)
			(stroke
				(width 0.1)
				(type default)
			)
			(layer "F.Fab")
		)
		(pad "1" smd rect
			(at -0.5334 0 180)
			(size 0.7112 0.6096)
			(layers "F.Cu" "F.Mask" "F.Paste")
			(net "SG")
		)
		(pad "2" smd rect
			(at 0.5334 0 180)
			(size 0.7112 0.6096)
			(layers "F.Cu" "F.Mask" "F.Paste")
			(net "UNNAMED_14_IS32FL3207QWLA3TRQFN")
		)
		(zone
			(layer "F.Cu")
			(hatch none 0.5)
			(connect_pads
				(clearance 0)
			)
			(min_thickness 0.25)
			(keepout
				(tracks allowed)
				(vias not_allowed)
				(pads allowed)
				(copperpour not_allowed)
				(footprints allowed)
			)
			(placement
				(enabled no)
				(sheetname "")
			)
			(fill
				(thermal_gap 0.5)
				(thermal_bridge_width 0.5)
				(island_removal_mode 0)
			)
			(polygon
				(pts
					(xy 111.2012 -99.7458) (xy 111.0488 -99.7458) (xy 111.0488 -99.1362) (xy 111.2012 -99.1362)
				)
			)
		)
		(zone
			(layer "F.Cu")
			(hatch none 0.5)
			(connect_pads
				(clearance 0)
			)
			(min_thickness 0.25)
			(keepout
				(tracks not_allowed)
				(vias allowed)
				(pads allowed)
				(copperpour not_allowed)
				(footprints allowed)
			)
			(placement
				(enabled no)
				(sheetname "")
			)
			(fill
				(thermal_gap 0.5)
				(thermal_bridge_width 0.5)
				(island_removal_mode 0)
			)
			(polygon
				(pts
					(xy 111.2012 -99.7458) (xy 111.0488 -99.7458) (xy 111.0488 -99.1362) (xy 111.2012 -99.1362)
				)
			)
		)
	)
	(footprint ""
		(layer "F.Cu")
		(at 150.381462 -59.182 180)
		(property "Reference" "R298"
			(at 1.410462 3.89763 0)
			(unlocked yes)
			(layer "F.SilkS")
			(effects
				(font
					(size 0.7874 0.5842)
					(thickness 0.1524)
				)
			)
		)
		(property "Value" "VAL*"
			(at 0.02032 2.13233 180)
			(unlocked yes)
			(layer "F.Fab")
			(hide yes)
			(effects
				(font
					(size 0.7874 0.5842)
					(thickness 0.1524)
				)
			)
		)
		(property "Tolerance" "TOL*"
			(at 0.044704 3.05435 180)
			(unlocked yes)
			(layer "Cmts.User")
			(hide yes)
			(effects
				(font
					(size 0.7874 0.5842)
					(thickness 0.1524)
				)
			)
		)
		(property "User Part Number" "PARTNUM*"
			(at 0.02032 4.024884 180)
			(unlocked yes)
			(layer "Cmts.User")
			(hide yes)
			(effects
				(font
					(size 0.7874 0.5842)
					(thickness 0.1524)
				)
			)
		)
		(property "Device Type" "RESISTOR-G155-133R0-01,33OHM,1%"
			(at 0.008382 1.210564 180)
			(unlocked yes)
			(layer "F.Fab")
			(hide yes)
			(effects
				(font
					(size 0.7874 0.5842)
					(thickness 0.1524)
				)
			)
		)
		(duplicate_pad_numbers_are_jumpers no)
		(fp_line
			(start 1.143 0.5588)
			(end 1.143 -0.5588)
			(stroke
				(width 0.1)
				(type default)
			)
			(layer "F.SilkS")
		)
		(fp_line
			(start 1.143 -0.5588)
			(end -1.143 -0.5588)
			(stroke
				(width 0.1)
				(type default)
			)
			(layer "F.SilkS")
		)
		(fp_line
			(start -1.143 0.5588)
			(end 1.143 0.5588)
			(stroke
				(width 0.1)
				(type default)
			)
			(layer "F.SilkS")
		)
		(fp_line
			(start -1.143 -0.5588)
			(end -1.143 0.5588)
			(stroke
				(width 0.1)
				(type default)
			)
			(layer "F.SilkS")
		)
		(fp_rect
			(start -1.143 0.5588)
			(end 1.143 -0.5588)
			(stroke
				(width 0)
				(type default)
			)
			(fill no)
			(layer "F.CrtYd")
		)
		(fp_line
			(start 0.508 0.3048)
			(end 0.508 -0.3048)
			(stroke
				(width 0.1)
				(type default)
			)
			(layer "F.Fab")
		)
		(fp_line
			(start 0.508 -0.3048)
			(end -0.508 -0.3048)
			(stroke
				(width 0.1)
				(type default)
			)
			(layer "F.Fab")
		)
		(fp_line
			(start -0.508 0.3048)
			(end 0.508 0.3048)
			(stroke
				(width 0.1)
				(type default)
			)
			(layer "F.Fab")
		)
		(fp_line
			(start -0.508 -0.3048)
			(end -0.508 0.3048)
			(stroke
				(width 0.1)
				(type default)
			)
			(layer "F.Fab")
		)
		(pad "1" smd rect
			(at -0.5334 0 180)
			(size 0.7112 0.6096)
			(layers "F.Cu" "F.Mask" "F.Paste")
			(net "R_SHT3X_RST_N")
		)
		(pad "2" smd rect
			(at 0.5334 0 180)
			(size 0.7112 0.6096)
			(layers "F.Cu" "F.Mask" "F.Paste")
			(net "FPGA_OUT_SHT3X_RST_N")
		)
		(zone
			(layer "F.Cu")
			(hatch none 0.5)
			(connect_pads
				(clearance 0)
			)
			(min_thickness 0.25)
			(keepout
				(tracks allowed)
				(vias not_allowed)
				(pads allowed)
				(copperpour not_allowed)
				(footprints allowed)
			)
			(placement
				(enabled no)
				(sheetname "")
			)
			(fill
				(thermal_gap 0.5)
				(thermal_bridge_width 0.5)
				(island_removal_mode 0)
			)
			(polygon
				(pts
					(xy 150.457662 -59.4868) (xy 150.305262 -59.4868) (xy 150.305262 -58.8772) (xy 150.457662 -58.8772)
				)
			)
		)
	)
)
